(kicad_pcb
	(version 20241229)
	(generator "pcbnew")
	(generator_version "9.0")
	(general
		(thickness 1.294)
		(legacy_teardrops no)
	)
	(paper "A3")
	(title_block
		(title "Kintex 410T devboard")
		(date "2024-04-03")
		(rev "1.1.2")
		(comment 9 "footprint 89 of 975 (J18), pads 447-533 of 564")
	)
	(layers
		(0 "F.Cu" mixed)
		(4 "In1.Cu" power)
		(6 "In2.Cu" power)
		(8 "In3.Cu" mixed)
		(10 "In4.Cu" power)
		(12 "In5.Cu" mixed)
		(14 "In6.Cu" power)
		(16 "In7.Cu" mixed)
		(18 "In8.Cu" power)
		(2 "B.Cu" mixed)
		(9 "F.Adhes" user "F.Adhesive")
		(11 "B.Adhes" user "B.Adhesive")
		(13 "F.Paste" user)
		(15 "B.Paste" user)
		(5 "F.SilkS" user "F.Silkscreen")
		(7 "B.SilkS" user "B.Silkscreen")
		(1 "F.Mask" user)
		(3 "B.Mask" user)
		(17 "Dwgs.User" user "User.Drawings")
		(19 "Cmts.User" user "User.Comments")
		(21 "Eco1.User" user "User.Eco1")
		(23 "Eco2.User" user "User.Eco2")
		(25 "Edge.Cuts" user)
		(27 "Margin" user)
		(31 "F.CrtYd" user "F.Courtyard")
		(29 "B.CrtYd" user "B.Courtyard")
		(35 "F.Fab" user)
		(33 "B.Fab" user)
	)
	(footprint "antmicro-footprints:ASP-184329-01_mounting_holes"
		(layer "F.Cu")
		(at 162.000001 106.000001 90)
		(property "Reference" "J18"
			(at 28.280001 4.299999 180)
			(layer "F.SilkS")
			(effects
				(font
					(size 0.7 0.7)
					(thickness 0.15)
				)
				(justify left bottom)
			)
		)
		(property "Value" "ASP-184329-01_mounting_holes"
			(at -8.4 0.2 90)
			(layer "F.Fab")
			(effects
				(font
					(size 0.7 0.7)
					(thickness 0.15)
				)
				(justify left bottom)
			)
		)
		(property "Description" "Mezzanine Connector, Array, Female, 1.27 mm, 14 Rows, 560 Contacts, Surface Mount"
			(at 0 0 90)
			(layer "F.Fab")
			(hide yes)
			(effects
				(font
					(size 1.27 1.27)
					(thickness 0.15)
				)
			)
		)
		(property "Author" "Antmicro"
			(at 268.000002 -56 0)
			(layer "F.Fab")
			(hide yes)
			(effects
				(font
					(size 1 1)
					(thickness 0.15)
				)
			)
		)
		(property "License" "Apache-2.0"
			(at 268.000002 -56 0)
			(layer "F.Fab")
			(hide yes)
			(effects
				(font
					(size 1 1)
					(thickness 0.15)
				)
			)
		)
		(property "MPN" "ASP-184329-01"
			(at 268.000002 -56 0)
			(layer "F.Fab")
			(hide yes)
			(effects
				(font
					(size 1 1)
					(thickness 0.15)
				)
			)
		)
		(property "Manufacturer" "Samtec"
			(at 268.000002 -56 0)
			(layer "F.Fab")
			(hide yes)
			(effects
				(font
					(size 1 1)
					(thickness 0.15)
				)
			)
		)
		(sheetname "FMC+ HSPC")
		(sheetfile "fmc-hspc.kicad_sch")
		(attr smd)
		(pad "M03" smd circle
			(at 22.225 -8.257 90)
			(size 0.64 0.64)
			(layers "F.Cu" "F.Mask")
			(net 248 "unconnected-(J18H-DP23_M2C_N-PadM03)")
			(pinfunction "DP23_M2C_N")
			(pintype "passive+no_connect")
		)
		(pad "M04" smd circle
			(at 20.954 -8.257 90)
			(size 0.64 0.64)
			(layers "F.Cu" "F.Mask")
			(net 1 "GND")
			(pinfunction "GND")
			(pintype "passive")
		)
		(pad "M05" smd circle
			(at 19.684 -8.257 90)
			(size 0.64 0.64)
			(layers "F.Cu" "F.Mask")
			(net 1 "GND")
			(pinfunction "GND")
			(pintype "passive")
		)
		(pad "M06" smd circle
			(at 18.414 -8.257 90)
			(size 0.64 0.64)
			(layers "F.Cu" "F.Mask")
			(net 251 "unconnected-(J18H-DP22_M2C_P-PadM06)")
			(pinfunction "DP22_M2C_P")
			(pintype "passive+no_connect")
		)
		(pad "M07" smd circle
			(at 17.144 -8.257 90)
			(size 0.64 0.64)
			(layers "F.Cu" "F.Mask")
			(net 252 "unconnected-(J18H-DP22_M2C_N-PadM07)")
			(pinfunction "DP22_M2C_N")
			(pintype "passive+no_connect")
		)
		(pad "M08" smd circle
			(at 15.874 -8.257 90)
			(size 0.64 0.64)
			(layers "F.Cu" "F.Mask")
			(net 1 "GND")
			(pinfunction "GND")
			(pintype "passive")
		)
		(pad "M09" smd circle
			(at 14.605 -8.257 90)
			(size 0.64 0.64)
			(layers "F.Cu" "F.Mask")
			(net 1 "GND")
			(pinfunction "GND")
			(pintype "passive")
		)
		(pad "M10" smd circle
			(at 13.335 -8.257 90)
			(size 0.64 0.64)
			(layers "F.Cu" "F.Mask")
			(net 253 "unconnected-(J18H-DP21_M2C_P-PadM10)")
			(pinfunction "DP21_M2C_P")
			(pintype "passive+no_connect")
		)
		(pad "M11" smd circle
			(at 12.063 -8.257 90)
			(size 0.64 0.64)
			(layers "F.Cu" "F.Mask")
			(net 255 "unconnected-(J18H-DP21_M2C_N-PadM11)")
			(pinfunction "DP21_M2C_N")
			(pintype "passive+no_connect")
		)
		(pad "M12" smd circle
			(at 10.794 -8.257 90)
			(size 0.64 0.64)
			(layers "F.Cu" "F.Mask")
			(net 1 "GND")
			(pinfunction "GND")
			(pintype "passive")
		)
		(pad "M13" smd circle
			(at 9.525 -8.257 90)
			(size 0.64 0.64)
			(layers "F.Cu" "F.Mask")
			(net 1 "GND")
			(pinfunction "GND")
			(pintype "passive")
		)
		(pad "M14" smd circle
			(at 8.255 -8.257 90)
			(size 0.64 0.64)
			(layers "F.Cu" "F.Mask")
			(net 256 "unconnected-(J18H-DP20_M2C_P-PadM14)")
			(pinfunction "DP20_M2C_P")
			(pintype "passive+no_connect")
		)
		(pad "M15" smd circle
			(at 6.985 -8.257 90)
			(size 0.64 0.64)
			(layers "F.Cu" "F.Mask")
			(net 258 "unconnected-(J18H-DP20_M2C_N-PadM15)")
			(pinfunction "DP20_M2C_N")
			(pintype "passive+no_connect")
		)
		(pad "M16" smd circle
			(at 5.714 -8.257 90)
			(size 0.64 0.64)
			(layers "F.Cu" "F.Mask")
			(net 1 "GND")
			(pinfunction "GND")
			(pintype "passive")
		)
		(pad "M17" smd circle
			(at 4.445 -8.257 90)
			(size 0.64 0.64)
			(layers "F.Cu" "F.Mask")
			(net 1 "GND")
			(pinfunction "GND")
			(pintype "passive")
		)
		(pad "M18" smd circle
			(at 3.173 -8.257 90)
			(size 0.64 0.64)
			(layers "F.Cu" "F.Mask")
			(net 259 "unconnected-(J18H-DP14_C2M_P-PadM18)")
			(pinfunction "DP14_C2M_P")
			(pintype "passive+no_connect")
		)
		(pad "M19" smd circle
			(at 1.904 -8.257 90)
			(size 0.64 0.64)
			(layers "F.Cu" "F.Mask")
			(net 261 "unconnected-(J18H-DP14_C2M_N-PadM19)")
			(pinfunction "DP14_C2M_N")
			(pintype "passive+no_connect")
		)
		(pad "M20" smd circle
			(at 0.633 -8.257 90)
			(size 0.64 0.64)
			(layers "F.Cu" "F.Mask")
			(net 1 "GND")
			(pinfunction "GND")
			(pintype "passive")
		)
		(pad "M21" smd circle
			(at -0.635 -8.257 90)
			(size 0.64 0.64)
			(layers "F.Cu" "F.Mask")
			(net 1 "GND")
			(pinfunction "GND")
			(pintype "passive")
		)
		(pad "M22" smd circle
			(at -1.905 -8.257 90)
			(size 0.64 0.64)
			(layers "F.Cu" "F.Mask")
			(net 262 "unconnected-(J18H-DP15_C2M_P-PadM22)")
			(pinfunction "DP15_C2M_P")
			(pintype "passive+no_connect")
		)
		(pad "M23" smd circle
			(at -3.176 -8.257 90)
			(size 0.64 0.64)
			(layers "F.Cu" "F.Mask")
			(net 263 "unconnected-(J18H-DP15_C2M_N-PadM23)")
			(pinfunction "DP15_C2M_N")
			(pintype "passive+no_connect")
		)
		(pad "M24" smd circle
			(at -4.446 -8.257 90)
			(size 0.64 0.64)
			(layers "F.Cu" "F.Mask")
			(net 1 "GND")
			(pinfunction "GND")
			(pintype "passive")
		)
		(pad "M25" smd circle
			(at -5.715 -8.257 90)
			(size 0.64 0.64)
			(layers "F.Cu" "F.Mask")
			(net 1 "GND")
			(pinfunction "GND")
			(pintype "passive")
		)
		(pad "M26" smd circle
			(at -6.986 -8.257 90)
			(size 0.64 0.64)
			(layers "F.Cu" "F.Mask")
			(net 264 "unconnected-(J18H-DP16_C2M_P-PadM26)")
			(pinfunction "DP16_C2M_P")
			(pintype "passive+no_connect")
		)
		(pad "M27" smd circle
			(at -8.257 -8.257 90)
			(size 0.64 0.64)
			(layers "F.Cu" "F.Mask")
			(net 266 "unconnected-(J18H-DP16_C2M_N-PadM27)")
			(pinfunction "DP16_C2M_N")
			(pintype "passive+no_connect")
		)
		(pad "M28" smd circle
			(at -9.526 -8.257 90)
			(size 0.64 0.64)
			(layers "F.Cu" "F.Mask")
			(net 1 "GND")
			(pinfunction "GND")
			(pintype "passive")
		)
		(pad "M29" smd circle
			(at -10.795 -8.257 90)
			(size 0.64 0.64)
			(layers "F.Cu" "F.Mask")
			(net 1 "GND")
			(pinfunction "GND")
			(pintype "passive")
		)
		(pad "M30" smd circle
			(at -12.065 -8.257 90)
			(size 0.64 0.64)
			(layers "F.Cu" "F.Mask")
			(net 269 "unconnected-(J18H-DP17_C2M_P-PadM30)")
			(pinfunction "DP17_C2M_P")
			(pintype "passive+no_connect")
		)
		(pad "M31" smd circle
			(at -13.337 -8.257 90)
			(size 0.64 0.64)
			(layers "F.Cu" "F.Mask")
			(net 270 "unconnected-(J18H-DP17_C2M_N-PadM31)")
			(pinfunction "DP17_C2M_N")
			(pintype "passive+no_connect")
		)
		(pad "M32" smd circle
			(at -14.606 -8.257 90)
			(size 0.64 0.64)
			(layers "F.Cu" "F.Mask")
			(net 1 "GND")
			(pinfunction "GND")
			(pintype "passive")
		)
		(pad "M33" smd circle
			(at -15.875 -8.257 90)
			(size 0.64 0.64)
			(layers "F.Cu" "F.Mask")
			(net 1 "GND")
			(pinfunction "GND")
			(pintype "passive")
		)
		(pad "M34" smd circle
			(at -17.145 -8.257 90)
			(size 0.64 0.64)
			(layers "F.Cu" "F.Mask")
			(net 271 "unconnected-(J18H-DP18_C2M_P-PadM34)")
			(pinfunction "DP18_C2M_P")
			(pintype "passive+no_connect")
		)
		(pad "M35" smd circle
			(at -18.415 -8.257 90)
			(size 0.64 0.64)
			(layers "F.Cu" "F.Mask")
			(net 272 "unconnected-(J18H-DP18_C2M_N-PadM35)")
			(pinfunction "DP18_C2M_N")
			(pintype "passive+no_connect")
		)
		(pad "M36" smd circle
			(at -19.685 -8.257 90)
			(size 0.64 0.64)
			(layers "F.Cu" "F.Mask")
			(net 1 "GND")
			(pinfunction "GND")
			(pintype "passive")
		)
		(pad "M37" smd circle
			(at -20.956 -8.257 90)
			(size 0.64 0.64)
			(layers "F.Cu" "F.Mask")
			(net 1 "GND")
			(pinfunction "GND")
			(pintype "passive")
		)
		(pad "M38" smd circle
			(at -22.226 -8.257 90)
			(size 0.64 0.64)
			(layers "F.Cu" "F.Mask")
			(net 273 "unconnected-(J18H-DP19_C2M_P-PadM38)")
			(pinfunction "DP19_C2M_P")
			(pintype "passive+no_connect")
		)
		(pad "M39" smd circle
			(at -23.497 -8.257 90)
			(size 0.64 0.64)
			(layers "F.Cu" "F.Mask")
			(net 274 "unconnected-(J18H-DP19_C2M_N-PadM39)")
			(pinfunction "DP19_C2M_N")
			(pintype "passive+no_connect")
		)
		(pad "M40" smd circle
			(at -24.767 -8.257 90)
			(size 0.64 0.64)
			(layers "F.Cu" "F.Mask")
			(net 1 "GND")
			(pinfunction "GND")
			(pintype "passive")
		)
		(pad "Y01" smd circle
			(at 24.765 8.255 90)
			(size 0.64 0.64)
			(layers "F.Cu" "F.Mask")
			(net 1 "GND")
			(pinfunction "GND")
			(pintype "passive")
		)
		(pad "Y02" smd circle
			(at 23.495 8.255 90)
			(size 0.64 0.64)
			(layers "F.Cu" "F.Mask")
			(net 275 "unconnected-(J18H-DP23_C2M_P-PadY02)")
			(pinfunction "DP23_C2M_P")
			(pintype "passive+no_connect")
		)
		(pad "Y03" smd circle
			(at 22.225 8.255 90)
			(size 0.64 0.64)
			(layers "F.Cu" "F.Mask")
			(net 277 "unconnected-(J18H-DP23_C2M_N-PadY03)")
			(pinfunction "DP23_C2M_N")
			(pintype "passive+no_connect")
		)
		(pad "Y04" smd circle
			(at 20.954 8.255 90)
			(size 0.64 0.64)
			(layers "F.Cu" "F.Mask")
			(net 1 "GND")
			(pinfunction "GND")
			(pintype "passive")
		)
		(pad "Y05" smd circle
			(at 19.684 8.255 90)
			(size 0.64 0.64)
			(layers "F.Cu" "F.Mask")
			(net 1 "GND")
			(pinfunction "GND")
			(pintype "passive")
		)
		(pad "Y06" smd circle
			(at 18.414 8.255 90)
			(size 0.64 0.64)
			(layers "F.Cu" "F.Mask")
			(net 280 "unconnected-(J18H-DP21_C2M_P-PadY06)")
			(pinfunction "DP21_C2M_P")
			(pintype "passive+no_connect")
		)
		(pad "Y07" smd circle
			(at 17.144 8.255 90)
			(size 0.64 0.64)
			(layers "F.Cu" "F.Mask")
			(net 281 "unconnected-(J18H-DP21_C2M_N-PadY07)")
			(pinfunction "DP21_C2M_N")
			(pintype "passive+no_connect")
		)
		(pad "Y08" smd circle
			(at 15.874 8.255 90)
			(size 0.64 0.64)
			(layers "F.Cu" "F.Mask")
			(net 1 "GND")
			(pinfunction "GND")
			(pintype "passive")
		)
		(pad "Y09" smd circle
			(at 14.605 8.255 90)
			(size 0.64 0.64)
			(layers "F.Cu" "F.Mask")
			(net 1 "GND")
			(pinfunction "GND")
			(pintype "passive")
		)
		(pad "Y10" smd circle
			(at 13.335 8.255 90)
			(size 0.64 0.64)
			(layers "F.Cu" "F.Mask")
			(net 284 "unconnected-(J18H-DP10_M2C_P-PadY10)")
			(pinfunction "DP10_M2C_P")
			(pintype "passive+no_connect")
		)
		(pad "Y11" smd circle
			(at 12.063 8.255 90)
			(size 0.64 0.64)
			(layers "F.Cu" "F.Mask")
			(net 285 "unconnected-(J18H-DP10_M2C_N-PadY11)")
			(pinfunction "DP10_M2C_N")
			(pintype "passive+no_connect")
		)
		(pad "Y12" smd circle
			(at 10.794 8.255 90)
			(size 0.64 0.64)
			(layers "F.Cu" "F.Mask")
			(net 1 "GND")
			(pinfunction "GND")
			(pintype "passive")
		)
		(pad "Y13" smd circle
			(at 9.525 8.255 90)
			(size 0.64 0.64)
			(layers "F.Cu" "F.Mask")
			(net 1 "GND")
			(pinfunction "GND")
			(pintype "passive")
		)
		(pad "Y14" smd circle
			(at 8.255 8.255 90)
			(size 0.64 0.64)
			(layers "F.Cu" "F.Mask")
			(net 286 "unconnected-(J18H-DP12_M2C_P-PadY14)")
			(pinfunction "DP12_M2C_P")
			(pintype "passive+no_connect")
		)
		(pad "Y15" smd circle
			(at 6.985 8.255 90)
			(size 0.64 0.64)
			(layers "F.Cu" "F.Mask")
			(net 289 "unconnected-(J18H-DP12_M2C_N-PadY15)")
			(pinfunction "DP12_M2C_N")
			(pintype "passive+no_connect")
		)
		(pad "Y16" smd circle
			(at 5.714 8.255 90)
			(size 0.64 0.64)
			(layers "F.Cu" "F.Mask")
			(net 1 "GND")
			(pinfunction "GND")
			(pintype "passive")
		)
		(pad "Y17" smd circle
			(at 4.445 8.255 90)
			(size 0.64 0.64)
			(layers "F.Cu" "F.Mask")
			(net 1 "GND")
			(pinfunction "GND")
			(pintype "passive")
		)
		(pad "Y18" smd circle
			(at 3.173 8.255 90)
			(size 0.64 0.64)
			(layers "F.Cu" "F.Mask")
			(net 290 "unconnected-(J18H-DP14_M2C_P-PadY18)")
			(pinfunction "DP14_M2C_P")
			(pintype "passive+no_connect")
		)
		(pad "Y19" smd circle
			(at 1.904 8.255 90)
			(size 0.64 0.64)
			(layers "F.Cu" "F.Mask")
			(net 291 "unconnected-(J18H-DP14_M2C_N-PadY19)")
			(pinfunction "DP14_M2C_N")
			(pintype "passive+no_connect")
		)
		(pad "Y20" smd circle
			(at 0.633 8.255 90)
			(size 0.64 0.64)
			(layers "F.Cu" "F.Mask")
			(net 1 "GND")
			(pinfunction "GND")
			(pintype "passive")
		)
		(pad "Y21" smd circle
			(at -0.635 8.255 90)
			(size 0.64 0.64)
			(layers "F.Cu" "F.Mask")
			(net 1 "GND")
			(pinfunction "GND")
			(pintype "passive")
		)
		(pad "Y22" smd circle
			(at -1.905 8.255 90)
			(size 0.64 0.64)
			(layers "F.Cu" "F.Mask")
			(net 292 "unconnected-(J18H-DP15_M2C_P-PadY22)")
			(pinfunction "DP15_M2C_P")
			(pintype "passive+no_connect")
		)
		(pad "Y23" smd circle
			(at -3.176 8.255 90)
			(size 0.64 0.64)
			(layers "F.Cu" "F.Mask")
			(net 293 "unconnected-(J18H-DP15_M2C_N-PadY23)")
			(pinfunction "DP15_M2C_N")
			(pintype "passive+no_connect")
		)
		(pad "Y24" smd circle
			(at -4.446 8.255 90)
			(size 0.64 0.64)
			(layers "F.Cu" "F.Mask")
			(net 1 "GND")
			(pinfunction "GND")
			(pintype "passive")
		)
		(pad "Y25" smd circle
			(at -5.715 8.255 90)
			(size 0.64 0.64)
			(layers "F.Cu" "F.Mask")
			(net 1 "GND")
			(pinfunction "GND")
			(pintype "passive")
		)
		(pad "Y26" smd circle
			(at -6.986 8.255 90)
			(size 0.64 0.64)
			(layers "F.Cu" "F.Mask")
			(net 294 "unconnected-(J18H-DP11_C2M_P-PadY26)")
			(pinfunction "DP11_C2M_P")
			(pintype "passive+no_connect")
		)
		(pad "Y27" smd circle
			(at -8.257 8.255 90)
			(size 0.64 0.64)
			(layers "F.Cu" "F.Mask")
			(net 295 "unconnected-(J18H-DP11_C2M_N-PadY27)")
			(pinfunction "DP11_C2M_N")
			(pintype "passive+no_connect")
		)
		(pad "Y28" smd circle
			(at -9.526 8.255 90)
			(size 0.64 0.64)
			(layers "F.Cu" "F.Mask")
			(net 1 "GND")
			(pinfunction "GND")
			(pintype "passive")
		)
		(pad "Y29" smd circle
			(at -10.795 8.255 90)
			(size 0.64 0.64)
			(layers "F.Cu" "F.Mask")
			(net 1 "GND")
			(pinfunction "GND")
			(pintype "passive")
		)
		(pad "Y30" smd circle
			(at -12.065 8.255 90)
			(size 0.64 0.64)
			(layers "F.Cu" "F.Mask")
			(net 296 "unconnected-(J18H-DP13_C2M_P-PadY30)")
			(pinfunction "DP13_C2M_P")
			(pintype "passive+no_connect")
		)
		(pad "Y31" smd circle
			(at -13.337 8.255 90)
			(size 0.64 0.64)
			(layers "F.Cu" "F.Mask")
			(net 297 "unconnected-(J18H-DP13_C2M_N-PadY31)")
			(pinfunction "DP13_C2M_N")
			(pintype "passive+no_connect")
		)
		(pad "Y32" smd circle
			(at -14.606 8.255 90)
			(size 0.64 0.64)
			(layers "F.Cu" "F.Mask")
			(net 1 "GND")
			(pinfunction "GND")
			(pintype "passive")
		)
		(pad "Y33" smd circle
			(at -15.875 8.255 90)
			(size 0.64 0.64)
			(layers "F.Cu" "F.Mask")
			(net 1 "GND")
			(pinfunction "GND")
			(pintype "passive")
		)
		(pad "Y34" smd circle
			(at -17.145 8.255 90)
			(size 0.64 0.64)
			(layers "F.Cu" "F.Mask")
			(net 302 "unconnected-(J18H-DP17_M2C_P-PadY34)")
			(pinfunction "DP17_M2C_P")
			(pintype "passive+no_connect")
		)
		(pad "Y35" smd circle
			(at -18.415 8.255 90)
			(size 0.64 0.64)
			(layers "F.Cu" "F.Mask")
			(net 303 "unconnected-(J18H-DP17_M2C_N-PadY35)")
			(pinfunction "DP17_M2C_N")
			(pintype "passive+no_connect")
		)
		(pad "Y36" smd circle
			(at -19.685 8.255 90)
			(size 0.64 0.64)
			(layers "F.Cu" "F.Mask")
			(net 1 "GND")
			(pinfunction "GND")
			(pintype "passive")
		)
		(pad "Y37" smd circle
			(at -20.956 8.255 90)
			(size 0.64 0.64)
			(layers "F.Cu" "F.Mask")
			(net 1 "GND")
			(pinfunction "GND")
			(pintype "passive")
		)
		(pad "Y38" smd circle
			(at -22.226 8.255 90)
			(size 0.64 0.64)
			(layers "F.Cu" "F.Mask")
			(net 304 "unconnected-(J18H-DP19_M2C_P-PadY38)")
			(pinfunction "DP19_M2C_P")
			(pintype "passive+no_connect")
		)
		(pad "Y39" smd circle
			(at -23.497 8.255 90)
			(size 0.64 0.64)
			(layers "F.Cu" "F.Mask")
			(net 305 "unconnected-(J18H-DP19_M2C_N-PadY39)")
			(pinfunction "DP19_M2C_N")
			(pintype "passive+no_connect")
		)
		(pad "Y40" smd circle
			(at -24.767 8.255 90)
			(size 0.64 0.64)
			(layers "F.Cu" "F.Mask")
			(net 1 "GND")
			(pinfunction "GND")
			(pintype "passive")
		)
		(pad "Z01" smd circle
			(at 24.765 6.985 90)
			(size 0.64 0.64)
			(layers "F.Cu" "F.Mask")
			(net 306 "unconnected-(J18B-HSPC_PRSNT_M2C_L-PadZ01)")
			(pinfunction "HSPC_PRSNT_M2C_L")
			(pintype "passive+no_connect")
		)
		(pad "Z02" smd circle
			(at 23.495 6.985 90)
			(size 0.64 0.64)
			(layers "F.Cu" "F.Mask")
			(net 1 "GND")
			(pinfunction "GND")
			(pintype "passive")
		)
		(pad "Z03" smd circle
			(at 22.225 6.985 90)
			(size 0.64 0.64)
			(layers "F.Cu" "F.Mask")
			(net 1 "GND")
			(pinfunction "GND")
			(pintype "passive")
		)
		(pad "Z04" smd circle
			(at 20.954 6.985 90)
			(size 0.64 0.64)
			(layers "F.Cu" "F.Mask")
			(net 308 "unconnected-(J18H-DP22_C2M_P-PadZ04)")
			(pinfunction "DP22_C2M_P")
			(pintype "passive+no_connect")
		)
		(pad "Z05" smd circle
			(at 19.684 6.985 90)
			(size 0.64 0.64)
			(layers "F.Cu" "F.Mask")
			(net 309 "unconnected-(J18H-DP22_C2M_N-PadZ05)")
			(pinfunction "DP22_C2M_N")
			(pintype "passive+no_connect")
		)
		(pad "Z06" smd circle
			(at 18.414 6.985 90)
			(size 0.64 0.64)
			(layers "F.Cu" "F.Mask")
			(net 1 "GND")
			(pinfunction "GND")
			(pintype "passive")
		)
		(pad "Z07" smd circle
			(at 17.144 6.985 90)
			(size 0.64 0.64)
			(layers "F.Cu" "F.Mask")
			(net 1 "GND")
			(pinfunction "GND")
			(pintype "passive")
		)
		(pad "Z08" smd circle
			(at 15.874 6.985 90)
			(size 0.64 0.64)
			(layers "F.Cu" "F.Mask")
			(net 310 "unconnected-(J18H-DP20_C2M_P-PadZ08)")
			(pinfunction "DP20_C2M_P")
			(pintype "passive+no_connect")
		)
		(pad "Z09" smd circle
			(at 14.605 6.985 90)
			(size 0.64 0.64)
			(layers "F.Cu" "F.Mask")
			(net 311 "unconnected-(J18H-DP20_C2M_N-PadZ09)")
			(pinfunction "DP20_C2M_N")
			(pintype "passive+no_connect")
		)
	)
)
